(kicad_pcb
	(version 20260206)
	(generator "pcbnew")
	(generator_version "10.0")
	(general
		(thickness 1.6)
		(legacy_teardrops no)
	)
	(paper "A4")
	(title_block
		(title "v1-chassis-manager — T6M_CM_d_v01_1031_1645.brd")
		(comment 1 "Open CloudServer (Microsoft) / footprints 846-854 of 2512")
	)
	(layers
		(0 "F.Cu" signal "TOP")
		(4 "In1.Cu" signal "GND1")
		(6 "In2.Cu" signal "IN1")
		(8 "In3.Cu" signal "VCC1")
		(10 "In4.Cu" signal "VCC2")
		(12 "In5.Cu" signal "GND2")
		(14 "In6.Cu" signal "IN2")
		(16 "In7.Cu" signal "IN3")
		(18 "In8.Cu" signal "GND3")
		(2 "B.Cu" signal "BOTTOM")
		(9 "F.Adhes" user "F.Adhesive")
		(11 "B.Adhes" user "B.Adhesive")
		(13 "F.Paste" user "Package Geometry/Pastemask Top")
		(15 "B.Paste" user "Package Geometry/Pastemask Bottom")
		(5 "F.SilkS" user "Ref Des/Silkscreen Top")
		(7 "B.SilkS" user "Ref Des/Silkscreen Bottom")
		(1 "F.Mask" user "Board Geometry/Soldermask Top")
		(3 "B.Mask" user "Board Geometry/Soldermask Bottom")
		(17 "Dwgs.User" user "User.Drawings")
		(19 "Cmts.User" user "User.Comments")
		(21 "Eco1.User" user "User.Eco1")
		(23 "Eco2.User" user "User.Eco2")
		(25 "Edge.Cuts" user "Board Geometry/Outline")
		(27 "Margin" user)
		(31 "F.CrtYd" user "Package Geometry/Place Bound Top")
		(29 "B.CrtYd" user "Package Geometry/Place Bound Bottom")
		(35 "F.Fab" user "Ref Des/Assembly Top")
		(33 "B.Fab" user "Ref Des/Assembly Bottom")
	)
	(footprint ""
		(layer "F.Cu")
		(at 64.622172 -154.448002)
		(property "Reference" "PC5"
			(at -32.154368 -5.388864 0)
			(unlocked yes)
			(layer "F.SilkS")
			(effects
				(font
					(size 0.7874 0.5842)
					(thickness 0.1524)
				)
				(justify left)
			)
		)
		(property "Value" ""
			(at 0 0 0)
			(layer "F.Fab")
			(effects
				(font
					(size 1.27 1.27)
				)
			)
		)
		(duplicate_pad_numbers_are_jumpers no)
		(fp_line
			(start -1.905 -0.8636)
			(end 1.905 -0.8636)
			(stroke
				(width 0.1524)
				(type default)
			)
			(layer "F.SilkS")
		)
		(fp_line
			(start -1.905 0.8636)
			(end -1.905 -0.8636)
			(stroke
				(width 0.1524)
				(type default)
			)
			(layer "F.SilkS")
		)
		(fp_line
			(start 0 0.8382)
			(end 0 -0.8382)
			(stroke
				(width 0.1524)
				(type default)
			)
			(layer "F.SilkS")
		)
		(fp_line
			(start 1.905 -0.8636)
			(end 1.905 0.8636)
			(stroke
				(width 0.1524)
				(type default)
			)
			(layer "F.SilkS")
		)
		(fp_line
			(start 1.905 0.8636)
			(end -1.905 0.8636)
			(stroke
				(width 0.1524)
				(type default)
			)
			(layer "F.SilkS")
		)
		(fp_rect
			(start -1.524 0.7366)
			(end 1.524 -0.7366)
			(stroke
				(width 0)
				(type default)
			)
			(fill no)
			(layer "F.CrtYd")
		)
		(pad "1" smd rect
			(at 0.94996 0)
			(size 1.1176 1.3716)
			(layers "F.Cu" "F.Mask" "F.Paste")
			(net "P5V_STB_NODE1")
		)
		(pad "2" smd rect
			(at -0.94996 0)
			(size 1.1176 1.3716)
			(layers "F.Cu" "F.Mask" "F.Paste")
			(net "GND")
		)
	)
	(footprint ""
		(layer "F.Cu")
		(at 141.00556 -114.383058 90)
		(property "Reference" "R21"
			(at -1.995678 3.165856 90)
			(unlocked yes)
			(layer "F.SilkS")
			(effects
				(font
					(size 0.7874 0.5842)
					(thickness 0.1524)
				)
				(justify left)
			)
		)
		(property "Value" ""
			(at 0 0 90)
			(layer "F.Fab")
			(effects
				(font
					(size 1.27 1.27)
				)
			)
		)
		(duplicate_pad_numbers_are_jumpers no)
		(fp_line
			(start 0.7874 -0.4064)
			(end 0.7874 0.4064)
			(stroke
				(width 0.1524)
				(type default)
			)
			(layer "F.SilkS")
		)
		(fp_line
			(start -0.7874 -0.4064)
			(end 0.7874 -0.4064)
			(stroke
				(width 0.1524)
				(type default)
			)
			(layer "F.SilkS")
		)
		(fp_line
			(start 0.7874 0.4064)
			(end -0.7874 0.4064)
			(stroke
				(width 0.1524)
				(type default)
			)
			(layer "F.SilkS")
		)
		(fp_line
			(start -0.7874 0.4064)
			(end -0.7874 -0.4064)
			(stroke
				(width 0.1524)
				(type default)
			)
			(layer "F.SilkS")
		)
		(fp_poly
			(pts
				(xy -0.508 0.2794) (xy -0.508 0.2286) (xy -0.635 0.2286) (xy -0.635 -0.254) (xy -0.5334 -0.254)
				(xy -0.5334 -0.2794) (xy 0.5334 -0.2794) (xy 0.5334 -0.254) (xy 0.635 -0.254) (xy 0.635 0.254) (xy 0.5334 0.254)
				(xy 0.5334 0.2794)
			)
			(stroke
				(width 0)
				(type default)
			)
			(fill no)
			(layer "F.CrtYd")
		)
		(pad "1" smd rect
			(at 0.40005 0 90)
			(size 0.4572 0.508)
			(layers "F.Cu" "F.Mask" "F.Paste")
			(net "CLKREQC_NODE1_N")
		)
		(pad "2" smd rect
			(at -0.40005 0 90)
			(size 0.4572 0.508)
			(layers "F.Cu" "F.Mask" "F.Paste")
			(net "P3V3_CLK_NODE1")
		)
	)
	(footprint ""
		(layer "F.Cu")
		(at 176.1236 -192.582292 -90)
		(property "Reference" ""
			(at 0 0 270)
			(layer "F.SilkS")
			(hide yes)
			(effects
				(font
					(size 1.27 1.27)
				)
			)
		)
		(property "Value" ""
			(at 0 0 270)
			(layer "F.Fab")
			(effects
				(font
					(size 1.27 1.27)
				)
			)
		)
		(duplicate_pad_numbers_are_jumpers no)
		(fp_poly
			(pts
				(arc
					(start 0 -1.4986)
					(mid 0 1.4986)
					(end 0 -1.4986)
				)
			)
			(stroke
				(width 0)
				(type default)
			)
			(fill no)
			(layer "F.CrtYd")
		)
		(pad "1" smd circle
			(at 0 0 270)
			(size 0.9906 0.9906)
			(layers "F.Cu" "F.Mask" "F.Paste")
			(net "Net_37")
		)
		(zone
			(layer "F.Cu")
			(hatch none 0.5)
			(connect_pads
				(clearance 0)
			)
			(min_thickness 0.25)
			(keepout
				(tracks not_allowed)
				(vias allowed)
				(pads allowed)
				(copperpour not_allowed)
				(footprints allowed)
			)
			(placement
				(enabled no)
				(sheetname "")
			)
			(fill
				(thermal_gap 0.5)
				(thermal_bridge_width 0.5)
				(island_removal_mode 0)
			)
			(polygon
				(pts
					(arc
						(start 177.7492 -192.582292)
						(mid 174.498 -192.582292)
						(end 177.7492 -192.582292)
					)
				)
			)
		)
	)
	(footprint ""
		(layer "F.Cu")
		(at 80.6831 -82.902044 180)
		(property "Reference" "R170"
			(at -0.219964 -16.94815 0)
			(unlocked yes)
			(layer "F.SilkS")
			(effects
				(font
					(size 0.7874 0.5842)
					(thickness 0.1524)
				)
				(justify left)
			)
		)
		(property "Value" ""
			(at 0 0 180)
			(layer "F.Fab")
			(effects
				(font
					(size 1.27 1.27)
				)
			)
		)
		(duplicate_pad_numbers_are_jumpers no)
		(fp_line
			(start 0.7874 0.4064)
			(end -0.7874 0.4064)
			(stroke
				(width 0.1524)
				(type default)
			)
			(layer "F.SilkS")
		)
		(fp_line
			(start 0.7874 -0.4064)
			(end 0.7874 0.4064)
			(stroke
				(width 0.1524)
				(type default)
			)
			(layer "F.SilkS")
		)
		(fp_line
			(start -0.7874 0.4064)
			(end -0.7874 -0.4064)
			(stroke
				(width 0.1524)
				(type default)
			)
			(layer "F.SilkS")
		)
		(fp_line
			(start -0.7874 -0.4064)
			(end 0.7874 -0.4064)
			(stroke
				(width 0.1524)
				(type default)
			)
			(layer "F.SilkS")
		)
		(fp_poly
			(pts
				(xy -0.508 0.2794) (xy -0.508 0.2286) (xy -0.635 0.2286) (xy -0.635 -0.254) (xy -0.5334 -0.254)
				(xy -0.5334 -0.2794) (xy 0.5334 -0.2794) (xy 0.5334 -0.254) (xy 0.635 -0.254) (xy 0.635 0.254) (xy 0.5334 0.254)
				(xy 0.5334 0.2794)
			)
			(stroke
				(width 0)
				(type default)
			)
			(fill no)
			(layer "F.CrtYd")
		)
		(pad "1" smd rect
			(at 0.40005 0 180)
			(size 0.4572 0.508)
			(layers "F.Cu" "F.Mask" "F.Paste")
			(net "LPC_CPU_NODE1_CLK0_DS")
		)
		(pad "2" smd rect
			(at -0.40005 0 180)
			(size 0.4572 0.508)
			(layers "F.Cu" "F.Mask" "F.Paste")
			(net "GND")
		)
	)
	(footprint ""
		(layer "F.Cu")
		(at 103.481124 -140.818108)
		(property "Reference" "PC97"
			(at -1.865122 -4.26085 0)
			(unlocked yes)
			(layer "F.SilkS")
			(effects
				(font
					(size 0.635 0.4064)
					(thickness 0.1524)
				)
				(justify left)
			)
		)
		(property "Value" ""
			(at 0 0 0)
			(layer "F.Fab")
			(effects
				(font
					(size 1.27 1.27)
				)
			)
		)
		(duplicate_pad_numbers_are_jumpers no)
		(fp_line
			(start -0.7874 -0.4064)
			(end 0.7874 -0.4064)
			(stroke
				(width 0.1524)
				(type default)
			)
			(layer "F.SilkS")
		)
		(fp_line
			(start -0.7874 0.4064)
			(end -0.7874 -0.4064)
			(stroke
				(width 0.1524)
				(type default)
			)
			(layer "F.SilkS")
		)
		(fp_line
			(start 0 0.381)
			(end 0 -0.381)
			(stroke
				(width 0.1524)
				(type default)
			)
			(layer "F.SilkS")
		)
		(fp_line
			(start 0.7874 -0.4064)
			(end 0.7874 0.4064)
			(stroke
				(width 0.1524)
				(type default)
			)
			(layer "F.SilkS")
		)
		(fp_line
			(start 0.7874 0.4064)
			(end -0.7874 0.4064)
			(stroke
				(width 0.1524)
				(type default)
			)
			(layer "F.SilkS")
		)
		(fp_poly
			(pts
				(xy -0.5334 0.254) (xy -0.635 0.254) (xy -0.635 0.2286) (xy -0.635 -0.254) (xy -0.5334 -0.254) (xy -0.5334 -0.2794)
				(xy 0.5334 -0.2794) (xy 0.5334 -0.254) (xy 0.635 -0.254) (xy 0.635 0.254) (xy 0.5334 0.254) (xy 0.5334 0.2794)
				(xy -0.508 0.2794) (xy -0.5334 0.2794)
			)
			(stroke
				(width 0)
				(type default)
			)
			(fill no)
			(layer "F.CrtYd")
		)
		(pad "1" smd rect
			(at 0.40005 0)
			(size 0.4572 0.508)
			(layers "F.Cu" "F.Mask" "F.Paste")
			(net "AGND_PVCCP_NODE1")
		)
		(pad "2" smd rect
			(at -0.40005 0)
			(size 0.4572 0.508)
			(layers "F.Cu" "F.Mask" "F.Paste")
			(net "P1V05_NODE1")
		)
	)
	(footprint ""
		(layer "F.Cu")
		(at 91.102434 -187.842398 180)
		(property "Reference" "C681"
			(at 1.437894 7.294372 0)
			(unlocked yes)
			(layer "F.SilkS")
			(effects
				(font
					(size 0.7874 0.5842)
					(thickness 0.1524)
				)
				(justify left)
			)
		)
		(property "Value" ""
			(at 0 0 180)
			(layer "F.Fab")
			(effects
				(font
					(size 1.27 1.27)
				)
			)
		)
		(duplicate_pad_numbers_are_jumpers no)
		(fp_line
			(start 0.7874 0.4064)
			(end -0.7874 0.4064)
			(stroke
				(width 0.1524)
				(type default)
			)
			(layer "F.SilkS")
		)
		(fp_line
			(start 0.7874 -0.4064)
			(end 0.7874 0.4064)
			(stroke
				(width 0.1524)
				(type default)
			)
			(layer "F.SilkS")
		)
		(fp_line
			(start 0 0.381)
			(end 0 -0.381)
			(stroke
				(width 0.1524)
				(type default)
			)
			(layer "F.SilkS")
		)
		(fp_line
			(start -0.7874 0.4064)
			(end -0.7874 -0.4064)
			(stroke
				(width 0.1524)
				(type default)
			)
			(layer "F.SilkS")
		)
		(fp_line
			(start -0.7874 -0.4064)
			(end 0.7874 -0.4064)
			(stroke
				(width 0.1524)
				(type default)
			)
			(layer "F.SilkS")
		)
		(fp_poly
			(pts
				(xy -0.5334 0.254) (xy -0.635 0.254) (xy -0.635 0.2286) (xy -0.635 -0.254) (xy -0.5334 -0.254) (xy -0.5334 -0.2794)
				(xy 0.5334 -0.2794) (xy 0.5334 -0.254) (xy 0.635 -0.254) (xy 0.635 0.254) (xy 0.5334 0.254) (xy 0.5334 0.2794)
				(xy -0.508 0.2794) (xy -0.5334 0.2794)
			)
			(stroke
				(width 0)
				(type default)
			)
			(fill no)
			(layer "F.CrtYd")
		)
		(pad "1" smd rect
			(at 0.40005 0 180)
			(size 0.4572 0.508)
			(layers "F.Cu" "F.Mask" "F.Paste")
			(net "UART_T5_NODE2_TXD_R")
		)
		(pad "2" smd rect
			(at -0.40005 0 180)
			(size 0.4572 0.508)
			(layers "F.Cu" "F.Mask" "F.Paste")
			(net "GND")
		)
	)
	(footprint ""
		(layer "F.Cu")
		(at 29.50591 -143.697706 90)
		(property "Reference" "C429"
			(at 0.004826 1.406144 90)
			(unlocked yes)
			(layer "F.SilkS")
			(effects
				(font
					(size 0.7874 0.5842)
					(thickness 0.1524)
				)
			)
		)
		(property "Value" ""
			(at 0 0 90)
			(layer "F.Fab")
			(effects
				(font
					(size 1.27 1.27)
				)
			)
		)
		(duplicate_pad_numbers_are_jumpers no)
		(fp_line
			(start 1.2954 -0.5842)
			(end 1.2954 0.5842)
			(stroke
				(width 0.1524)
				(type default)
			)
			(layer "F.SilkS")
		)
		(fp_line
			(start 0 -0.5842)
			(end 0 0.5842)
			(stroke
				(width 0.1524)
				(type default)
			)
			(layer "F.SilkS")
		)
		(fp_line
			(start -1.2954 -0.5842)
			(end 1.2954 -0.5842)
			(stroke
				(width 0.1524)
				(type default)
			)
			(layer "F.SilkS")
		)
		(fp_line
			(start 1.2954 0.5842)
			(end -1.2954 0.5842)
			(stroke
				(width 0.1524)
				(type default)
			)
			(layer "F.SilkS")
		)
		(fp_line
			(start -1.2954 0.5842)
			(end -1.2954 -0.5842)
			(stroke
				(width 0.1524)
				(type default)
			)
			(layer "F.SilkS")
		)
		(fp_poly
			(pts
				(xy 0.8636 -0.4572) (xy 0.8636 -0.3556) (xy 1.143 -0.3556) (xy 1.143 0.3556) (xy 0.8636 0.3556)
				(xy 0.8636 0.4572) (xy -0.8636 0.4572) (xy -0.8636 0.3556) (xy -1.143 0.3556) (xy -1.143 -0.3556)
				(xy -0.8636 -0.3556) (xy -0.8636 -0.4572)
			)
			(stroke
				(width 0)
				(type default)
			)
			(fill no)
			(layer "F.CrtYd")
		)
		(fp_line
			(start 0.884936 -0.504952)
			(end 0.884936 0.504952)
			(stroke
				(width 0.1)
				(type default)
			)
			(layer "F.Fab")
		)
		(fp_line
			(start -0.884936 -0.504952)
			(end 0.884936 -0.504952)
			(stroke
				(width 0.1)
				(type default)
			)
			(layer "F.Fab")
		)
		(fp_line
			(start 0.884936 0.504952)
			(end -0.884936 0.504952)
			(stroke
				(width 0.1)
				(type default)
			)
			(layer "F.Fab")
		)
		(fp_line
			(start -0.884936 0.504952)
			(end -0.884936 -0.504952)
			(stroke
				(width 0.1)
				(type default)
			)
			(layer "F.Fab")
		)
		(pad "1" smd rect
			(at 0.7366 0 180)
			(size 0.7112 0.8128)
			(layers "F.Cu" "F.Mask" "F.Paste")
			(net "LAN1_CTRL_P1V9_R")
		)
		(pad "2" smd rect
			(at -0.7366 0 180)
			(size 0.7112 0.8128)
			(layers "F.Cu" "F.Mask" "F.Paste")
			(net "P1V9_LAN1")
		)
	)
	(footprint ""
		(layer "F.Cu")
		(at 6.64083 -138.632184 -90)
		(property "Reference" "R1311"
			(at 4.294632 4.254246 90)
			(unlocked yes)
			(layer "F.SilkS")
			(effects
				(font
					(size 0.7874 0.5842)
					(thickness 0.1524)
				)
				(justify left)
			)
		)
		(property "Value" ""
			(at 0 0 270)
			(layer "F.Fab")
			(effects
				(font
					(size 1.27 1.27)
				)
			)
		)
		(duplicate_pad_numbers_are_jumpers no)
		(fp_line
			(start -0.7874 0.4064)
			(end -0.7874 -0.4064)
			(stroke
				(width 0.1524)
				(type default)
			)
			(layer "F.SilkS")
		)
		(fp_line
			(start 0.7874 0.4064)
			(end -0.7874 0.4064)
			(stroke
				(width 0.1524)
				(type default)
			)
			(layer "F.SilkS")
		)
		(fp_line
			(start -0.7874 -0.4064)
			(end 0.7874 -0.4064)
			(stroke
				(width 0.1524)
				(type default)
			)
			(layer "F.SilkS")
		)
		(fp_line
			(start 0.7874 -0.4064)
			(end 0.7874 0.4064)
			(stroke
				(width 0.1524)
				(type default)
			)
			(layer "F.SilkS")
		)
		(fp_poly
			(pts
				(xy -0.508 0.2794) (xy -0.508 0.2286) (xy -0.635 0.2286) (xy -0.635 -0.254) (xy -0.5334 -0.254)
				(xy -0.5334 -0.2794) (xy 0.5334 -0.2794) (xy 0.5334 -0.254) (xy 0.635 -0.254) (xy 0.635 0.254) (xy 0.5334 0.254)
				(xy 0.5334 0.2794)
			)
			(stroke
				(width 0)
				(type default)
			)
			(fill no)
			(layer "F.CrtYd")
		)
		(pad "1" smd rect
			(at 0.40005 0 270)
			(size 0.4572 0.508)
			(layers "F.Cu" "F.Mask" "F.Paste")
			(net "P3V3_NODE1")
		)
		(pad "2" smd rect
			(at -0.40005 0 270)
			(size 0.4572 0.508)
			(layers "F.Cu" "F.Mask" "F.Paste")
			(net "UART_RI_P6_LS_N")
		)
	)
	(footprint ""
		(layer "F.Cu")
		(at 11.576812 -11.613896 -90)
		(property "Reference" "R218"
			(at 0.984758 4.672076 90)
			(unlocked yes)
			(layer "F.SilkS")
			(effects
				(font
					(size 0.7874 0.5842)
					(thickness 0.1524)
				)
				(justify left)
			)
		)
		(property "Value" ""
			(at 0 0 270)
			(layer "F.Fab")
			(effects
				(font
					(size 1.27 1.27)
				)
			)
		)
		(duplicate_pad_numbers_are_jumpers no)
		(fp_line
			(start -0.7874 0.4064)
			(end -0.7874 -0.4064)
			(stroke
				(width 0.1524)
				(type default)
			)
			(layer "F.SilkS")
		)
		(fp_line
			(start 0.7874 0.4064)
			(end -0.7874 0.4064)
			(stroke
				(width 0.1524)
				(type default)
			)
			(layer "F.SilkS")
		)
		(fp_line
			(start -0.7874 -0.4064)
			(end 0.7874 -0.4064)
			(stroke
				(width 0.1524)
				(type default)
			)
			(layer "F.SilkS")
		)
		(fp_line
			(start 0.7874 -0.4064)
			(end 0.7874 0.4064)
			(stroke
				(width 0.1524)
				(type default)
			)
			(layer "F.SilkS")
		)
		(fp_poly
			(pts
				(xy -0.508 0.2794) (xy -0.508 0.2286) (xy -0.635 0.2286) (xy -0.635 -0.254) (xy -0.5334 -0.254)
				(xy -0.5334 -0.2794) (xy 0.5334 -0.2794) (xy 0.5334 -0.254) (xy 0.635 -0.254) (xy 0.635 0.254) (xy 0.5334 0.254)
				(xy 0.5334 0.2794)
			)
			(stroke
				(width 0)
				(type default)
			)
			(fill no)
			(layer "F.CrtYd")
		)
		(pad "1" smd rect
			(at 0.40005 0 270)
			(size 0.4572 0.508)
			(layers "F.Cu" "F.Mask" "F.Paste")
			(net "PV_VDDR_NODE1_VREF_R")
		)
		(pad "2" smd rect
			(at -0.40005 0 270)
			(size 0.4572 0.508)
			(layers "F.Cu" "F.Mask" "F.Paste")
			(net "GND")
		)
	)
)
